# S9S_MB_2U (Grand Teton) — schematic netlist excerpt (pin names and nets, part order shuffled) for the footprints in the layout excerpt that follows; sources: Cadence DE-HDL packaged netlist, KiCad conversion of 03242023_DA0F0TMBIJ0_F0T_Motherboard_J_brd_V01_OCP.brd

J1  SCONN288_ADR50017P130CC  SCONN288_ADR50017-P130CC IO  pkg DDR288S_1-1VXB  page 82
  VIN_BULK0  = P12V_S3_AUX_CPU0_NVDIMM
  RFU0  = TP_CHA_CPU0_DIMM1_FRU_0
  VIN_MGMT  = P3V3_AUX
  HSCL  = I3C_SPD_DDRABCD_CPU0_LVC1_SCL_R
  HSDA  = I3C_SPD_DDRABCD_CPU0_LVC1_SDA
  VSS0  = GND
  DQ0_A  = M_A_CPU0_SA_DQ<0>
  VSS1  = GND
  DQ1_A  = M_A_CPU0_SA_DQ<1>
  VSS2  = GND
  DQS0_A_T  = M_A_CPU0_SA_DQS_DP<0>
  DQS0_A_C  = M_A_CPU0_SA_DQS_DN<0>
  VSS3  = GND
  DQ4_A  = M_A_CPU0_SA_DQ<4>
  VSS4  = GND
  DQ5_A  = M_A_CPU0_SA_DQ<5>
  VSS5  = GND
  DQ8_A  = M_A_CPU0_SA_DQ<8>
  VSS6  = GND
  DQ9_A  = M_A_CPU0_SA_DQ<9>
  VSS7  = GND
  DQS1_A_T  = M_A_CPU0_SA_DQS_DP<1>
  DQS1_A_C  = M_A_CPU0_SA_DQS_DN<1>
  VSS8  = GND
  DQ12_A  = M_A_CPU0_SA_DQ<12>
  VSS9  = GND
  DQ13_A  = M_A_CPU0_SA_DQ<13>
  VSS10  = GND
  DQ16_A  = M_A_CPU0_SA_DQ<16>
  VSS11  = GND
  DQ17_A  = M_A_CPU0_SA_DQ<17>
  VSS12  = GND
  DQS2_A_T  = M_A_CPU0_SA_DQS_DP<2>
  DQS2_A_C  = M_A_CPU0_SA_DQS_DN<2>
  VSS13  = GND
  DQ20_A  = M_A_CPU0_SA_DQ<20>
  VSS14  = GND
  DQ21_A  = M_A_CPU0_SA_DQ<21>
  VSS15  = GND
  DQ24_A  = M_A_CPU0_SA_DQ<24>
  VSS16  = GND
  DQ25_A  = M_A_CPU0_SA_DQ<25>
  VSS17  = GND
  DQS3_A_T  = M_A_CPU0_SA_DQS_DP<3>
  DQS3_A_C  = M_A_CPU0_SA_DQS_DN<3>
  VSS18  = GND
  DQ28_A  = M_A_CPU0_SA_DQ<28>
  VSS19  = GND
  DQ29_A  = M_A_CPU0_SA_DQ<29>
  VSS20  = GND
  CB0_A  = M_A_CPU0_SA_CB<0>
  VSS21  = GND
  CB1_A  = M_A_CPU0_SA_CB<1>
  VSS22  = GND
  DQS4_A_T  = M_A_CPU0_SA_DQS_DP<4>
  DQS4_A_C  = M_A_CPU0_SA_DQS_DN<4>
  VSS23  = GND
  CB4_A  = M_A_CPU0_SA_CB<4>
  VSS24  = GND
  CB5_A  = M_A_CPU0_SA_CB<5>
  VSS25  = GND
  ALERT_N  = M_A_CPU0_ALERT_N
  VSS26  = GND
  CS0_A_N  = M_A_CPU0_SA_CS_N<0>
  VSS27  = GND
  CA0_A  = M_A_CPU0_SA_CA<0>
  VSS28  = GND
  CA2_A  = M_A_CPU0_SA_CA<2>
  VSS29  = GND
  CA4_A  = M_A_CPU0_SA_CA<4>
  VSS30  = GND
  CA6_A  = M_A_CPU0_SA_CA<6>
  VSS31  = GND
  PAR_A  = M_A_CPU0_SA_PAR
  VSS32  = GND
  CA0_B  = M_A_CPU0_SB_CA<0>
  VSS33  = GND
  CA2_B  = M_A_CPU0_SB_CA<2>
  VSS34  = GND
  CA4_B  = M_A_CPU0_SB_CA<4>
  VSS35  = GND
  CA6_B  = M_A_CPU0_SB_CA<6>
  VSS36  = GND
  CS0_B_N  = M_A_CPU0_SB_CS_N<0>
  VSS37  = GND
  \lbd||rsp_a_n\  = M_A_CPU0_SA_RSP<0>
  \lbs||rsp_b_n\  = M_A_CPU0_SB_RSP<0>
  VSS38  = GND
  CB4_B  = M_A_CPU0_SB_CB<4>
  VSS39  = GND
  CB5_B  = M_A_CPU0_SB_CB<5>
  VSS40  = GND
  \dqs9_b_t||tdqs9_b_t||dbi4_b_n\  = M_A_CPU0_SB_DQS_DP<9>
  \dqs9_b_c||tdqs9_b_c\  = M_A_CPU0_SB_DQS_DN<9>
  VSS41  = GND
  CB0_B  = M_A_CPU0_SB_CB<0>
  VSS42  = GND
  CB1_B  = M_A_CPU0_SB_CB<1>
  VSS43  = GND
  DQ0_B  = M_A_CPU0_SB_DQ<0>
  VSS44  = GND
  DQ1_B  = M_A_CPU0_SB_DQ<1>
  VSS45  = GND
  DQS0_B_T  = M_A_CPU0_SB_DQS_DP<0>
  DQS0_B_C  = M_A_CPU0_SB_DQS_DN<0>
  VSS46  = GND
  DQ4_B  = M_A_CPU0_SB_DQ<4>
  VSS47  = GND
  DQ5_B  = M_A_CPU0_SB_DQ<5>
  VSS48  = GND
  DQ8_B  = M_A_CPU0_SB_DQ<8>
  VSS49  = GND
  DQ9_B  = M_A_CPU0_SB_DQ<9>
  VSS50  = GND
  DQS1_B_T  = M_A_CPU0_SB_DQS_DP<1>
  DQS1_B_C  = M_A_CPU0_SB_DQS_DN<1>
  VSS51  = GND
  DQ12_B  = M_A_CPU0_SB_DQ<12>
  VSS52  = GND
  DQ13_B  = M_A_CPU0_SB_DQ<13>
  VSS53  = GND
  DQ16_B  = M_A_CPU0_SB_DQ<16>
  VSS54  = GND
  DQ17_B  = M_A_CPU0_SB_DQ<17>
  VSS55  = GND
  DQS2_B_T  = M_A_CPU0_SB_DQS_DP<2>
  DQS2_B_C  = M_A_CPU0_SB_DQS_DN<2>
  VSS56  = GND
  DQ20_B  = M_A_CPU0_SB_DQ<20>
  VSS57  = GND
  DQ21_B  = M_A_CPU0_SB_DQ<21>
  VSS58  = GND
  DQ24_B  = M_A_CPU0_SB_DQ<24>
  VSS59  = GND
  DQ25_B  = M_A_CPU0_SB_DQ<25>
  VSS60  = GND
  DQS3_B_T  = M_A_CPU0_SB_DQS_DP<3>
  DQS3_B_C  = M_A_CPU0_SB_DQS_DN<3>
  VSS61  = GND
  DQ28_B  = M_A_CPU0_SB_DQ<28>
  VSS62  = GND
  DQ29_B  = M_A_CPU0_SB_DQ<29>
  VSS63  = GND
  RFU1  = TP_CHA_CPU0_DIMM1_FRU_1
  VIN_BULK1  = P12V_S3_AUX_CPU0_NVDIMM
  VIN_BULK2  = P12V_S3_AUX_CPU0_NVDIMM
  \pwr_good||fail_n\  = PWRGD_CHA_CPU0_DIMM1
  HSA  = PD_CHA_CPU0_DIMM1_SAA
  RFU2  = TP_CHA_CPU0_DIMM1_FRU_2
  RFU3  = TP_CHA_CPU0_DIMM1_FRU_3
  VSS64  = GND
  DQ2_A  = M_A_CPU0_SA_DQ<2>
  VSS65  = GND
  DQ3_A  = M_A_CPU0_SA_DQ<3>
  VSS66  = GND
  \dqs5_a_c||tdqs5_a_c||dqs5_a_t||tdqs5_a_t\  = M_A_CPU0_SA_DQS_DN<5>
  \dqs5_a_t||tdqs5_a_t\  = M_A_CPU0_SA_DQS_DP<5>
  VSS67  = GND
  DQ6_A  = M_A_CPU0_SA_DQ<6>
  VSS68  = GND
  DQ7_A  = M_A_CPU0_SA_DQ<7>
  VSS69  = GND
  DQ10_A  = M_A_CPU0_SA_DQ<10>
  VSS70  = GND
  DQ11_A  = M_A_CPU0_SA_DQ<11>
  VSS71  = GND
  \dqs6_a_c||tdqs6_a_c||dqs6_a_t||tdqs6_a_t\  = M_A_CPU0_SA_DQS_DN<6>
  \dqs6_a_t||tdqs6_a_t\  = M_A_CPU0_SA_DQS_DP<6>
  VSS72  = GND
  DQ14_A  = M_A_CPU0_SA_DQ<14>
  VSS73  = GND
  DQ15_A  = M_A_CPU0_SA_DQ<15>
  VSS74  = GND
  DQ18_A  = M_A_CPU0_SA_DQ<18>
  VSS75  = GND
  DQ19_A  = M_A_CPU0_SA_DQ<19>
  VSS76  = GND
  \dqs7_a_c||tdqs7_a_c\  = M_A_CPU0_SA_DQS_DN<7>
  \dqs7_a_t||tdqs7_a_t\  = M_A_CPU0_SA_DQS_DP<7>
  VSS77  = GND
  DQ22_A  = M_A_CPU0_SA_DQ<22>
  VSS78  = GND
  DQ23_A  = M_A_CPU0_SA_DQ<23>
  VSS79  = GND
  DQ26_A  = M_A_CPU0_SA_DQ<26>
  VSS80  = GND
  DQ27_A  = M_A_CPU0_SA_DQ<27>
  VSS81  = GND
  \dqs8_a_c||tdqs8_a_c\  = M_A_CPU0_SA_DQS_DN<8>
  \dqs8_a_t||tdqs8_a_t\  = M_A_CPU0_SA_DQS_DP<8>
  VSS82  = GND
  DQ30_A  = M_A_CPU0_SA_DQ<30>
  VSS83  = GND
  DQ31_A  = M_A_CPU0_SA_DQ<31>
  VSS84  = GND
  CB2_A  = M_A_CPU0_SA_CB<2>
  VSS85  = GND
  CB3_A  = M_A_CPU0_SA_CB<3>
  VSS86  = GND
  \dqs9_a_c||tdqs9_a_c\  = M_A_CPU0_SA_DQS_DN<9>
  \dqs9_a_t||tdqs9_a_t\  = M_A_CPU0_SA_DQS_DP<9>
  VSS87  = GND
  CB6_A  = M_A_CPU0_SA_CB<6>
  VSS88  = GND
  CB7_A  = M_A_CPU0_SA_CB<7>
  VSS89  = GND
  RESET_N  = RST_M_AB_CPU0_FPGA_N
  VSS90  = GND
  CS1_A_N  = M_A_CPU0_SA_CS_N<1>
  VSS91  = GND
  CA1_A  = M_A_CPU0_SA_CA<1>
  VSS92  = GND
  CA3_A  = M_A_CPU0_SA_CA<3>
  VSS93  = GND
  CA5_A  = M_A_CPU0_SA_CA<5>
  VSS94  = GND
  CK_T  = M_A_CPU0_CLK_DP<0>
  CK_C  = M_A_CPU0_CLK_DN<0>
  VSS95  = GND
  RFU4  = TP_CHA_CPU0_DIMM1_FRU_4
  CA1_B  = M_A_CPU0_SB_CA<1>
  VSS96  = GND
  CA3_B  = M_A_CPU0_SB_CA<3>
  VSS97  = GND
  CA5_B  = M_A_CPU0_SB_CA<5>
  VSS98  = GND
  PAR_B  = M_A_CPU0_SB_PAR
  VSS99  = GND
  CS1_B_N  = M_A_CPU0_SB_CS_N<1>
  VSS100  = GND
  RFU5  = TP_CHA_CPU0_DIMM1_FRU_5
  RFU6  = TP_CHA_CPU0_DIMM1_FRU_6
  VSS101  = GND
  CB6_B  = M_A_CPU0_SB_CB<6>
  VSS102  = GND
  CB7_B  = M_A_CPU0_SB_CB<7>
  VSS103  = GND
  DQS4_B_C  = M_A_CPU0_SB_DQS_DN<4>
  DQS4_B_T  = M_A_CPU0_SB_DQS_DP<4>
  VSS104  = GND
  CB2_B  = M_A_CPU0_SB_CB<2>
  VSS105  = GND
  CB3_B  = M_A_CPU0_SB_CB<3>
  VSS106  = GND
  DQ2_B  = M_A_CPU0_SB_DQ<2>
  VSS107  = GND
  DQ3_B  = M_A_CPU0_SB_DQ<3>
  VSS108  = GND
  \dqs5_b_c||tdqs5_b_c\  = M_A_CPU0_SB_DQS_DN<5>
  \dqs5_b_t||tdqs5_b_t\  = M_A_CPU0_SB_DQS_DP<5>
  VSS109  = GND
  DQ6_B  = M_A_CPU0_SB_DQ<6>
  VSS110  = GND
  DQ7_B  = M_A_CPU0_SB_DQ<7>
  VSS111  = GND
  DQ10_B  = M_A_CPU0_SB_DQ<10>
  VSS112  = GND
  DQ11_B  = M_A_CPU0_SB_DQ<11>
  VSS113  = GND
  \dqs6_b_c||tdqs6_b_c\  = M_A_CPU0_SB_DQS_DN<6>
  \dqs6_b_t||tdqs6_b_t\  = M_A_CPU0_SB_DQS_DP<6>
  VSS114  = GND
  DQ14_B  = M_A_CPU0_SB_DQ<14>
  VSS115  = GND
  DQ15_B  = M_A_CPU0_SB_DQ<15>
  VSS116  = GND
  DQ18_B  = M_A_CPU0_SB_DQ<18>
  VSS117  = GND
  DQ19_B  = M_A_CPU0_SB_DQ<19>
  VSS118  = GND
  \dqs7_b_c||tdqs7_b_c\  = M_A_CPU0_SB_DQS_DN<7>
  \dqs7_b_t||tdqs7_b_t\  = M_A_CPU0_SB_DQS_DP<7>
  VSS119  = GND
  DQ22_B  = M_A_CPU0_SB_DQ<22>
  VSS120  = GND
  DQ23_B  = M_A_CPU0_SB_DQ<23>
  VSS121  = GND
  DQ26_B  = M_A_CPU0_SB_DQ<26>
  VSS122  = GND
  DQ27_B  = M_A_CPU0_SB_DQ<27>
  VSS123  = GND
  \dqs8_b_c||tdqs8_b_c\  = M_A_CPU0_SB_DQS_DN<8>
  \dqs8_b_t||tdqs8_b_t\  = M_A_CPU0_SB_DQS_DP<8>
  VSS124  = GND
  DQ30_B  = M_A_CPU0_SB_DQ<30>
  VSS125  = GND
  DQ31_B  = M_A_CPU0_SB_DQ<31>
  VSS126  = GND
  G1  = GND
  G2  = GND
  G3  = GND

(kicad_pcb
	(version 20260206)
	(generator "pcbnew")
	(generator_version "10.0")
	(general
		(thickness 1.6)
		(legacy_teardrops no)
	)
	(paper "A4")
	(title_block
		(title "03242023_DA0F0TMBIJ0_F0T_Motherboard_J_brd_V01_OCP.brd")
		(comment 1 "Grand Teton / footprint 1236 of 6105 (J1), pads 183-228 of 291")
	)
	(layers
		(0 "F.Cu" signal "TOP")
		(4 "In1.Cu" signal "GND")
		(6 "In2.Cu" signal "IN1")
		(8 "In3.Cu" signal "GND1")
		(10 "In4.Cu" signal "IN2")
		(12 "In5.Cu" signal "GND2")
		(14 "In6.Cu" signal "IN3")
		(16 "In7.Cu" signal "GND3")
		(18 "In8.Cu" signal "VCC")
		(20 "In9.Cu" signal "VCC1")
		(22 "In10.Cu" signal "GND4")
		(24 "In11.Cu" signal "IN4")
		(26 "In12.Cu" signal "GND5")
		(28 "In13.Cu" signal "IN5")
		(30 "In14.Cu" signal "GND6")
		(32 "In15.Cu" signal "IN6")
		(34 "In16.Cu" signal "GND7")
		(2 "B.Cu" signal "BOTTOM")
		(9 "F.Adhes" user "F.Adhesive")
		(11 "B.Adhes" user "B.Adhesive")
		(13 "F.Paste" user "Package Geometry/Pastemask Top")
		(15 "B.Paste" user "Package Geometry/Pastemask Bottom")
		(5 "F.SilkS" user "Ref Des/Silkscreen Top")
		(7 "B.SilkS" user "Ref Des/Silkscreen Bottom")
		(1 "F.Mask" user "Board Geometry/Soldermask Top")
		(3 "B.Mask" user "Board Geometry/Soldermask Bottom")
		(17 "Dwgs.User" user "User.Drawings")
		(19 "Cmts.User" user "User.Comments")
		(21 "Eco1.User" user "User.Eco1")
		(23 "Eco2.User" user "User.Eco2")
		(25 "Edge.Cuts" user "Board Geometry/Outline")
		(27 "Margin" user)
		(31 "F.CrtYd" user "Package Geometry/Place Bound Top")
		(29 "B.CrtYd" user "Package Geometry/Place Bound Bottom")
		(35 "F.Fab" user "Ref Des/Assembly Top")
		(33 "B.Fab" user "Ref Des/Assembly Bottom")
	)
	(footprint ""
		(layer "F.Cu")
		(at 303.393348 -258.091686)
		(property "Reference" "J1"
			(at -3.683 -81.702148 0)
			(unlocked yes)
			(layer "F.SilkS")
			(effects
				(font
					(size 0.7874 0.5842)
					(thickness 0.1524)
				)
				(justify left)
			)
		)
		(property "Value" ""
			(at 0 0 0)
			(layer "F.Fab")
			(effects
				(font
					(size 1.27 1.27)
				)
			)
		)
		(duplicate_pad_numbers_are_jumpers no)
		(pad "183" smd rect
			(at 2.050034 -31.025084 270)
			(size 0.519938 1.4986)
			(layers "F.Cu" "F.Mask" "F.Paste")
			(net "M_A_CPU0_SA_DQ<23>")
		)
		(pad "184" smd rect
			(at 2.050034 -30.174946 270)
			(size 0.519938 1.4986)
			(layers "F.Cu" "F.Mask" "F.Paste")
			(net "GND")
		)
		(pad "185" smd rect
			(at 2.050034 -29.325062 270)
			(size 0.519938 1.4986)
			(layers "F.Cu" "F.Mask" "F.Paste")
			(net "M_A_CPU0_SA_DQ<26>")
		)
		(pad "186" smd rect
			(at 2.050034 -28.474924 270)
			(size 0.519938 1.4986)
			(layers "F.Cu" "F.Mask" "F.Paste")
			(net "GND")
		)
		(pad "187" smd rect
			(at 2.050034 -27.62504 270)
			(size 0.519938 1.4986)
			(layers "F.Cu" "F.Mask" "F.Paste")
			(net "M_A_CPU0_SA_DQ<27>")
		)
		(pad "188" smd rect
			(at 2.050034 -26.774902 270)
			(size 0.519938 1.4986)
			(layers "F.Cu" "F.Mask" "F.Paste")
			(net "GND")
		)
		(pad "189" smd rect
			(at 2.050034 -25.925018 270)
			(size 0.519938 1.4986)
			(layers "F.Cu" "F.Mask" "F.Paste")
			(net "M_A_CPU0_SA_DQS_DN<8>")
		)
		(pad "190" smd rect
			(at 2.050034 -25.07488 270)
			(size 0.519938 1.4986)
			(layers "F.Cu" "F.Mask" "F.Paste")
			(net "M_A_CPU0_SA_DQS_DP<8>")
		)
		(pad "191" smd rect
			(at 2.050034 -24.224996 270)
			(size 0.519938 1.4986)
			(layers "F.Cu" "F.Mask" "F.Paste")
			(net "GND")
		)
		(pad "192" smd rect
			(at 2.050034 -23.375112 270)
			(size 0.519938 1.4986)
			(layers "F.Cu" "F.Mask" "F.Paste")
			(net "M_A_CPU0_SA_DQ<30>")
		)
		(pad "193" smd rect
			(at 2.050034 -22.524974 270)
			(size 0.519938 1.4986)
			(layers "F.Cu" "F.Mask" "F.Paste")
			(net "GND")
		)
		(pad "194" smd rect
			(at 2.050034 -21.67509 270)
			(size 0.519938 1.4986)
			(layers "F.Cu" "F.Mask" "F.Paste")
			(net "M_A_CPU0_SA_DQ<31>")
		)
		(pad "195" smd rect
			(at 2.050034 -20.824952 270)
			(size 0.519938 1.4986)
			(layers "F.Cu" "F.Mask" "F.Paste")
			(net "GND")
		)
		(pad "196" smd rect
			(at 2.050034 -19.975068 270)
			(size 0.519938 1.4986)
			(layers "F.Cu" "F.Mask" "F.Paste")
			(net "M_A_CPU0_SA_CB<2>")
		)
		(pad "197" smd rect
			(at 2.050034 -19.12493 270)
			(size 0.519938 1.4986)
			(layers "F.Cu" "F.Mask" "F.Paste")
			(net "GND")
		)
		(pad "198" smd rect
			(at 2.050034 -18.275046 270)
			(size 0.519938 1.4986)
			(layers "F.Cu" "F.Mask" "F.Paste")
			(net "M_A_CPU0_SA_CB<3>")
		)
		(pad "199" smd rect
			(at 2.050034 -17.424908 270)
			(size 0.519938 1.4986)
			(layers "F.Cu" "F.Mask" "F.Paste")
			(net "GND")
		)
		(pad "200" smd rect
			(at 2.050034 -16.575024 270)
			(size 0.519938 1.4986)
			(layers "F.Cu" "F.Mask" "F.Paste")
			(net "M_A_CPU0_SA_DQS_DN<9>")
		)
		(pad "201" smd rect
			(at 2.050034 -15.724886 270)
			(size 0.519938 1.4986)
			(layers "F.Cu" "F.Mask" "F.Paste")
			(net "M_A_CPU0_SA_DQS_DP<9>")
		)
		(pad "202" smd rect
			(at 2.050034 -14.875002 270)
			(size 0.519938 1.4986)
			(layers "F.Cu" "F.Mask" "F.Paste")
			(net "GND")
		)
		(pad "203" smd rect
			(at 2.050034 -14.025118 270)
			(size 0.519938 1.4986)
			(layers "F.Cu" "F.Mask" "F.Paste")
			(net "M_A_CPU0_SA_CB<6>")
		)
		(pad "204" smd rect
			(at 2.050034 -13.17498 270)
			(size 0.519938 1.4986)
			(layers "F.Cu" "F.Mask" "F.Paste")
			(net "GND")
		)
		(pad "205" smd rect
			(at 2.050034 -12.325096 270)
			(size 0.519938 1.4986)
			(layers "F.Cu" "F.Mask" "F.Paste")
			(net "M_A_CPU0_SA_CB<7>")
		)
		(pad "206" smd rect
			(at 2.050034 -11.474958 270)
			(size 0.519938 1.4986)
			(layers "F.Cu" "F.Mask" "F.Paste")
			(net "GND")
		)
		(pad "207" smd rect
			(at 2.050034 -10.625074 270)
			(size 0.519938 1.4986)
			(layers "F.Cu" "F.Mask" "F.Paste")
			(net "RST_M_AB_CPU0_FPGA_N")
		)
		(pad "208" smd rect
			(at 2.050034 -9.774936 270)
			(size 0.519938 1.4986)
			(layers "F.Cu" "F.Mask" "F.Paste")
			(net "GND")
		)
		(pad "209" smd rect
			(at 2.050034 -8.925052 270)
			(size 0.519938 1.4986)
			(layers "F.Cu" "F.Mask" "F.Paste")
			(net "M_A_CPU0_SA_CS_N<1>")
		)
		(pad "210" smd rect
			(at 2.050034 -8.074914 270)
			(size 0.519938 1.4986)
			(layers "F.Cu" "F.Mask" "F.Paste")
			(net "GND")
		)
		(pad "211" smd rect
			(at 2.050034 -7.22503 270)
			(size 0.519938 1.4986)
			(layers "F.Cu" "F.Mask" "F.Paste")
			(net "M_A_CPU0_SA_CA<1>")
		)
		(pad "212" smd rect
			(at 2.050034 -6.374892 270)
			(size 0.519938 1.4986)
			(layers "F.Cu" "F.Mask" "F.Paste")
			(net "GND")
		)
		(pad "213" smd rect
			(at 2.050034 -5.525008 270)
			(size 0.519938 1.4986)
			(layers "F.Cu" "F.Mask" "F.Paste")
			(net "M_A_CPU0_SA_CA<3>")
		)
		(pad "214" smd rect
			(at 2.050034 -4.675124 270)
			(size 0.519938 1.4986)
			(layers "F.Cu" "F.Mask" "F.Paste")
			(net "GND")
		)
		(pad "215" smd rect
			(at 2.050034 -3.824986 270)
			(size 0.519938 1.4986)
			(layers "F.Cu" "F.Mask" "F.Paste")
			(net "M_A_CPU0_SA_CA<5>")
		)
		(pad "216" smd rect
			(at 2.050034 -2.975102 270)
			(size 0.519938 1.4986)
			(layers "F.Cu" "F.Mask" "F.Paste")
			(net "GND")
		)
		(pad "217" smd rect
			(at 2.050034 -2.124964 270)
			(size 0.519938 1.4986)
			(layers "F.Cu" "F.Mask" "F.Paste")
			(net "M_A_CPU0_CLK_DP<0>")
		)
		(pad "218" smd rect
			(at 2.050034 -1.27508 270)
			(size 0.519938 1.4986)
			(layers "F.Cu" "F.Mask" "F.Paste")
			(net "M_A_CPU0_CLK_DN<0>")
		)
		(pad "219" smd rect
			(at 2.050034 -0.424942 270)
			(size 0.519938 1.4986)
			(layers "F.Cu" "F.Mask" "F.Paste")
			(net "GND")
		)
		(pad "220" smd rect
			(at 2.050034 5.525008 270)
			(size 0.519938 1.4986)
			(layers "F.Cu" "F.Mask" "F.Paste")
			(net "TP_CHA_CPU0_DIMM1_FRU_4")
		)
		(pad "221" smd rect
			(at 2.050034 6.374892 270)
			(size 0.519938 1.4986)
			(layers "F.Cu" "F.Mask" "F.Paste")
			(net "M_A_CPU0_SB_CA<1>")
		)
		(pad "222" smd rect
			(at 2.050034 7.22503 270)
			(size 0.519938 1.4986)
			(layers "F.Cu" "F.Mask" "F.Paste")
			(net "GND")
		)
		(pad "223" smd rect
			(at 2.050034 8.074914 270)
			(size 0.519938 1.4986)
			(layers "F.Cu" "F.Mask" "F.Paste")
			(net "M_A_CPU0_SB_CA<3>")
		)
		(pad "224" smd rect
			(at 2.050034 8.925052 270)
			(size 0.519938 1.4986)
			(layers "F.Cu" "F.Mask" "F.Paste")
			(net "GND")
		)
		(pad "225" smd rect
			(at 2.050034 9.774936 270)
			(size 0.519938 1.4986)
			(layers "F.Cu" "F.Mask" "F.Paste")
			(net "M_A_CPU0_SB_CA<5>")
		)
		(pad "226" smd rect
			(at 2.050034 10.625074 270)
			(size 0.519938 1.4986)
			(layers "F.Cu" "F.Mask" "F.Paste")
			(net "GND")
		)
		(pad "227" smd rect
			(at 2.050034 11.474958 270)
			(size 0.519938 1.4986)
			(layers "F.Cu" "F.Mask" "F.Paste")
			(net "M_A_CPU0_SB_PAR")
		)
		(pad "228" smd rect
			(at 2.050034 12.325096 270)
			(size 0.519938 1.4986)
			(layers "F.Cu" "F.Mask" "F.Paste")
			(net "GND")
		)
	)
)
